(kicad_pcb
	(version 20240108)
	(generator "pcbnew")
	(generator_version "8.0")
	(general
		(thickness 1.6)
		(legacy_teardrops no)
	)
	(paper "A4")
	(title_block
		(title "Jetson Orin Baseboard OCuLink Expansion")
		(date "2025-03-18")
		(rev "1.1.0")
		(company "Antmicro Ltd")
		(comment 1 "www.antmicro.com")
		(comment 9 "footprints 1-5 of 119")
	)
	(layers
		(0 "F.Cu" signal)
		(1 "In1.Cu" signal)
		(2 "In2.Cu" signal)
		(31 "B.Cu" signal)
		(32 "B.Adhes" user "B.Adhesive")
		(33 "F.Adhes" user "F.Adhesive")
		(34 "B.Paste" user)
		(35 "F.Paste" user)
		(36 "B.SilkS" user "B.Silkscreen")
		(37 "F.SilkS" user "F.Silkscreen")
		(38 "B.Mask" user)
		(39 "F.Mask" user)
		(40 "Dwgs.User" user "User.Drawings")
		(41 "Cmts.User" user "User.Comments")
		(42 "Eco1.User" user "User.Eco1")
		(43 "Eco2.User" user "User.Eco2")
		(44 "Edge.Cuts" user)
		(45 "Margin" user)
		(46 "B.CrtYd" user "B.Courtyard")
		(47 "F.CrtYd" user "F.Courtyard")
		(48 "B.Fab" user)
		(49 "F.Fab" user)
	)
	(footprint "antmicro-footprints:R_0402_1005Metric"
		(layer "F.Cu")
		(at 121.73 136.96 -90)
		(descr "Resistor SMD 0402")
		(tags "resistor SMD 0402")
		(property "Reference" "R35"
			(at -1.13 -1.66 90)
			(layer "F.SilkS")
			(effects
				(font
					(size 0.7 0.7)
					(thickness 0.15)
				)
				(justify right top)
			)
		)
		(property "Value" "R_0R_0402"
			(at -1.011843 1.772047 90)
			(layer "F.Fab")
			(effects
				(font
					(size 0.7 0.7)
					(thickness 0.15)
				)
				(justify right top)
			)
		)
		(property "Footprint" "antmicro-footprints:R_0402_1005Metric"
			(at 0 0 90)
			(layer "F.Fab")
			(hide yes)
			(effects
				(font
					(size 1.27 1.27)
					(thickness 0.15)
				)
			)
		)
		(property "Datasheet" "https://industrial.panasonic.com/cdbs/www-data/pdf/RDA0000/AOA0000C301.pdf"
			(at 0 0 90)
			(layer "F.Fab")
			(hide yes)
			(effects
				(font
					(size 1.27 1.27)
					(thickness 0.15)
				)
			)
		)
		(property "Description" "SMD Chip Resistor, Jumper, 0 ohm, 100 mW, 0402 [1005 Metric], Thick Film, General Purpose"
			(at 0 0 90)
			(layer "F.Fab")
			(hide yes)
			(effects
				(font
					(size 1.27 1.27)
					(thickness 0.15)
				)
			)
		)
		(property "MPN" "ERJ2GE0R00X"
			(at 0 0 -90)
			(unlocked yes)
			(layer "F.Fab")
			(hide yes)
			(effects
				(font
					(size 1 1)
					(thickness 0.15)
				)
			)
		)
		(property "Manufacturer" "Panasonic"
			(at 0 0 -90)
			(unlocked yes)
			(layer "F.Fab")
			(hide yes)
			(effects
				(font
					(size 1 1)
					(thickness 0.15)
				)
			)
		)
		(property "License" "Apache-2.0"
			(at 0 0 -90)
			(unlocked yes)
			(layer "F.Fab")
			(hide yes)
			(effects
				(font
					(size 1 1)
					(thickness 0.15)
				)
			)
		)
		(property "Author" "Antmicro"
			(at 0 0 -90)
			(unlocked yes)
			(layer "F.Fab")
			(hide yes)
			(effects
				(font
					(size 1 1)
					(thickness 0.15)
				)
			)
		)
		(property "Val" "0R"
			(at 0 0 -90)
			(unlocked yes)
			(layer "F.Fab")
			(hide yes)
			(effects
				(font
					(size 1 1)
					(thickness 0.15)
				)
			)
		)
		(property "Tolerance" ""
			(at 0 0 -90)
			(unlocked yes)
			(layer "F.Fab")
			(hide yes)
			(effects
				(font
					(size 1 1)
					(thickness 0.15)
				)
			)
		)
		(property "Current" "1A"
			(at 0 0 -90)
			(unlocked yes)
			(layer "F.Fab")
			(hide yes)
			(effects
				(font
					(size 1 1)
					(thickness 0.15)
				)
			)
		)
		(sheetname "Root")
		(sheetfile "jetson-orin-baseboard-oculink-expansion.kicad_sch")
		(attr smd)
		(fp_rect
			(start -0.925 -0.47)
			(end 0.925 0.47)
			(stroke
				(width 0.05)
				(type default)
			)
			(fill none)
			(layer "F.CrtYd")
		)
		(fp_rect
			(start -0.5 -0.25)
			(end 0.5 0.25)
			(stroke
				(width 0.15)
				(type solid)
			)
			(fill none)
			(layer "F.Fab")
		)
		(fp_text user "Author: Antmicro"
			(at -0.95 4.169 90)
			(layer "F.Fab")
			(hide yes)
			(effects
				(font
					(size 0.7 0.7)
					(thickness 0.15)
				)
				(justify right top)
			)
		)
		(fp_text user "${REFERENCE}"
			(at -0.95 3.168 90)
			(layer "F.Fab")
			(hide yes)
			(effects
				(font
					(size 0.7 0.7)
					(thickness 0.15)
				)
				(justify right top)
			)
		)
		(fp_text user "License: Apache-2.0"
			(at -0.95 5.169 90)
			(layer "F.Fab")
			(hide yes)
			(effects
				(font
					(size 0.7 0.7)
					(thickness 0.15)
				)
				(justify right top)
			)
		)
		(pad "1" smd roundrect
			(at -0.48 0 270)
			(size 0.59 0.64)
			(layers "F.Cu" "F.Paste" "F.Mask")
			(roundrect_rratio 0.25)
			(net 61 "/I2C_SDA")
			(pintype "passive")
		)
		(pad "2" smd roundrect
			(at 0.48 0 270)
			(size 0.59 0.64)
			(layers "F.Cu" "F.Paste" "F.Mask")
			(roundrect_rratio 0.25)
			(net 125 "Net-(J1-SDA)")
			(pintype "passive")
		)
	)
	(footprint "antmicro-footprints:R_0402_1005Metric"
		(layer "F.Cu")
		(at 142.3 145.4 -90)
		(descr "Resistor SMD 0402")
		(tags "resistor SMD 0402")
		(property "Reference" "R1"
			(at 1.863 0.308 90)
			(layer "F.SilkS")
			(effects
				(font
					(size 0.7 0.7)
					(thickness 0.15)
				)
				(justify right top)
			)
		)
		(property "Value" "R_0R_0402"
			(at -1.011843 1.772047 90)
			(layer "F.Fab")
			(hide yes)
			(effects
				(font
					(size 0.7 0.7)
					(thickness 0.15)
				)
				(justify right top)
			)
		)
		(property "Footprint" "antmicro-footprints:R_0402_1005Metric"
			(at 0 0 90)
			(layer "F.Fab")
			(hide yes)
			(effects
				(font
					(size 1.27 1.27)
					(thickness 0.15)
				)
			)
		)
		(property "Datasheet" "https://industrial.panasonic.com/cdbs/www-data/pdf/RDA0000/AOA0000C301.pdf"
			(at 0 0 90)
			(layer "F.Fab")
			(hide yes)
			(effects
				(font
					(size 1.27 1.27)
					(thickness 0.15)
				)
			)
		)
		(property "Description" "SMD Chip Resistor, Jumper, 0 ohm, 100 mW, 0402 [1005 Metric], Thick Film, General Purpose"
			(at 0 0 90)
			(layer "F.Fab")
			(hide yes)
			(effects
				(font
					(size 1.27 1.27)
					(thickness 0.15)
				)
			)
		)
		(property "MPN" "ERJ2GE0R00X"
			(at 0 0 -90)
			(unlocked yes)
			(layer "F.Fab")
			(hide yes)
			(effects
				(font
					(size 1 1)
					(thickness 0.15)
				)
			)
		)
		(property "Manufacturer" "Panasonic"
			(at 0 0 -90)
			(unlocked yes)
			(layer "F.Fab")
			(hide yes)
			(effects
				(font
					(size 1 1)
					(thickness 0.15)
				)
			)
		)
		(property "License" "Apache-2.0"
			(at 0 0 -90)
			(unlocked yes)
			(layer "F.Fab")
			(hide yes)
			(effects
				(font
					(size 1 1)
					(thickness 0.15)
				)
			)
		)
		(property "Author" "Antmicro"
			(at 0 0 -90)
			(unlocked yes)
			(layer "F.Fab")
			(hide yes)
			(effects
				(font
					(size 1 1)
					(thickness 0.15)
				)
			)
		)
		(property "Val" "0R"
			(at 0 0 -90)
			(unlocked yes)
			(layer "F.Fab")
			(hide yes)
			(effects
				(font
					(size 1 1)
					(thickness 0.15)
				)
			)
		)
		(property "Tolerance" ""
			(at 0 0 -90)
			(unlocked yes)
			(layer "F.Fab")
			(hide yes)
			(effects
				(font
					(size 1 1)
					(thickness 0.15)
				)
			)
		)
		(property "Current" "1A"
			(at 0 0 -90)
			(unlocked yes)
			(layer "F.Fab")
			(hide yes)
			(effects
				(font
					(size 1 1)
					(thickness 0.15)
				)
			)
		)
		(sheetname "Root")
		(sheetfile "jetson-orin-baseboard-oculink-expansion.kicad_sch")
		(attr smd)
		(fp_rect
			(start -0.925 -0.47)
			(end 0.925 0.47)
			(stroke
				(width 0.05)
				(type default)
			)
			(fill none)
			(layer "F.CrtYd")
		)
		(fp_rect
			(start -0.5 -0.25)
			(end 0.5 0.25)
			(stroke
				(width 0.15)
				(type solid)
			)
			(fill none)
			(layer "F.Fab")
		)
		(fp_text user "Author: Antmicro"
			(at -0.95 4.169 90)
			(layer "F.Fab")
			(hide yes)
			(effects
				(font
					(size 0.7 0.7)
					(thickness 0.15)
				)
				(justify right top)
			)
		)
		(fp_text user "License: Apache-2.0"
			(at -0.95 5.169 90)
			(layer "F.Fab")
			(hide yes)
			(effects
				(font
					(size 0.7 0.7)
					(thickness 0.15)
				)
				(justify right top)
			)
		)
		(fp_text user "${REFERENCE}"
			(at -0.95 3.168 90)
			(layer "F.Fab")
			(hide yes)
			(effects
				(font
					(size 0.7 0.7)
					(thickness 0.15)
				)
				(justify right top)
			)
		)
		(pad "1" smd roundrect
			(at -0.48 0 270)
			(size 0.59 0.64)
			(layers "F.Cu" "F.Paste" "F.Mask")
			(roundrect_rratio 0.25)
			(net 71 "/~{CPRSNT}")
			(pintype "passive")
		)
		(pad "2" smd roundrect
			(at 0.48 0 270)
			(size 0.59 0.64)
			(layers "F.Cu" "F.Paste" "F.Mask")
			(roundrect_rratio 0.25)
			(net 66 "Net-(J1-~{CPRSNT})")
			(pintype "passive")
		)
	)
	(footprint "antmicro-footprints:TSOT23-6"
		(layer "F.Cu")
		(at 144 124.201 -90)
		(property "Reference" "U5"
			(at 1.199 -1.55 90)
			(layer "F.SilkS")
			(effects
				(font
					(size 0.7 0.7)
					(thickness 0.15)
				)
				(justify right top)
			)
		)
		(property "Value" "~"
			(at 0 2.6 90)
			(layer "F.Fab")
			(effects
				(font
					(size 0.7 0.7)
					(thickness 0.15)
				)
				(justify right top)
			)
		)
		(property "Footprint" "antmicro-footprints:TSOT23-6"
			(at 0 0 90)
			(layer "F.Fab")
			(hide yes)
			(effects
				(font
					(size 1.27 1.27)
					(thickness 0.15)
				)
			)
		)
		(property "Datasheet" "https://www.mouser.com/datasheet/2/115/DIOD_S_A0008958405_1-2543193.pdf"
			(at 0 0 90)
			(layer "F.Fab")
			(hide yes)
			(effects
				(font
					(size 1.27 1.27)
					(thickness 0.15)
				)
			)
		)
		(property "Description" "Power Load Distribution Switch, High Side, Active High, 1 Output, 5.5 V, 3.6 A, 0.04 ohm, TSOT-26-6"
			(at 0 0 90)
			(layer "F.Fab")
			(hide yes)
			(effects
				(font
					(size 1.27 1.27)
					(thickness 0.15)
				)
			)
		)
		(property "MPN" "AP22615AWU-7"
			(at 0 0 -90)
			(unlocked yes)
			(layer "F.Fab")
			(hide yes)
			(effects
				(font
					(size 1 1)
					(thickness 0.15)
				)
			)
		)
		(property "Manufacturer" "Diodes Incorporated"
			(at 0 0 -90)
			(unlocked yes)
			(layer "F.Fab")
			(hide yes)
			(effects
				(font
					(size 1 1)
					(thickness 0.15)
				)
			)
		)
		(property "Author" "Antmicro"
			(at 0 0 -90)
			(unlocked yes)
			(layer "F.Fab")
			(hide yes)
			(effects
				(font
					(size 1 1)
					(thickness 0.15)
				)
			)
		)
		(property "License" "Apache-2.0"
			(at 0 0 -90)
			(unlocked yes)
			(layer "F.Fab")
			(hide yes)
			(effects
				(font
					(size 1 1)
					(thickness 0.15)
				)
			)
		)
		(sheetname "Root")
		(sheetfile "jetson-orin-baseboard-oculink-expansion.kicad_sch")
		(attr smd)
		(fp_line
			(start -1 1.55)
			(end -1 1.4)
			(stroke
				(width 0.15)
				(type solid)
			)
			(layer "F.SilkS")
		)
		(fp_line
			(start 1 1.55)
			(end -1 1.55)
			(stroke
				(width 0.15)
				(type solid)
			)
			(layer "F.SilkS")
		)
		(fp_line
			(start 1 1.55)
			(end 1 1.4)
			(stroke
				(width 0.15)
				(type solid)
			)
			(layer "F.SilkS")
		)
		(fp_line
			(start 1 -1.497)
			(end 1 -1.375)
			(stroke
				(width 0.15)
				(type solid)
			)
			(layer "F.SilkS")
		)
		(fp_line
			(start 1 -1.497)
			(end -1 -1.5)
			(stroke
				(width 0.15)
				(type solid)
			)
			(layer "F.SilkS")
		)
		(fp_line
			(start -1 -1.5)
			(end -1 -1.375)
			(stroke
				(width 0.15)
				(type solid)
			)
			(layer "F.SilkS")
		)
		(fp_circle
			(center -1.44 -1.5)
			(end -1.39 -1.5)
			(stroke
				(width 0.15)
				(type solid)
			)
			(fill solid)
			(layer "F.SilkS")
		)
		(fp_rect
			(start 1.93 -1.7)
			(end -1.93 1.7)
			(stroke
				(width 0.05)
				(type solid)
			)
			(fill none)
			(layer "F.CrtYd")
		)
		(fp_line
			(start -0.45 -1.521)
			(end -0.876 -1.096)
			(stroke
				(width 0.15)
				(type solid)
			)
			(layer "F.Fab")
		)
		(fp_rect
			(start 0.875 1.528)
			(end -0.875 -1.525)
			(stroke
				(width 0.15)
				(type solid)
			)
			(fill none)
			(layer "F.Fab")
		)
		(fp_text user "License: Apache-2.0"
			(at -1.93 6.199 90)
			(layer "F.Fab")
			(hide yes)
			(effects
				(font
					(size 0.7 0.7)
					(thickness 0.15)
				)
				(justify right top)
			)
		)
		(fp_text user "${REFERENCE}"
			(at -1.93 3.8 90)
			(layer "F.Fab")
			(hide yes)
			(effects
				(font
					(size 0.7 0.7)
					(thickness 0.15)
				)
				(justify right top)
			)
		)
		(fp_text user "Author: Antmicro"
			(at -1.93 5 90)
			(layer "F.Fab")
			(hide yes)
			(effects
				(font
					(size 0.7 0.7)
					(thickness 0.15)
				)
				(justify right top)
			)
		)
		(pad "1" smd rect
			(at -1.301 -0.947 180)
			(size 0.7 1.2)
			(layers "F.Cu" "F.Paste" "F.Mask")
			(net 135 "Net-(U5-OUT)")
			(pinfunction "OUT")
			(pintype "power_out")
		)
		(pad "2" smd rect
			(at -1.301 0.004 180)
			(size 0.7 1.2)
			(layers "F.Cu" "F.Paste" "F.Mask")
			(net 51 "GND")
			(pinfunction "GND")
			(pintype "power_in")
		)
		(pad "3" smd rect
			(at -1.301 0.954 180)
			(size 0.7 1.2)
			(layers "F.Cu" "F.Paste" "F.Mask")
			(net 138 "Net-(U5-FLG)")
			(pinfunction "FLG")
			(pintype "output")
		)
		(pad "4" smd rect
			(at 1.299 0.954 180)
			(size 0.7 1.2)
			(layers "F.Cu" "F.Paste" "F.Mask")
			(net 52 "+5V")
			(pinfunction "EN")
			(pintype "input")
		)
		(pad "5" smd rect
			(at 1.299 0.004 180)
			(size 0.7 1.2)
			(layers "F.Cu" "F.Paste" "F.Mask")
			(net 139 "Net-(U5-ISET)")
			(pinfunction "ISET")
			(pintype "passive")
		)
		(pad "6" smd rect
			(at 1.299 -0.947 180)
			(size 0.7 1.2)
			(layers "F.Cu" "F.Paste" "F.Mask")
			(net 52 "+5V")
			(pinfunction "IN")
			(pintype "power_in")
		)
	)
	(footprint "antmicro-footprints:R_0402_1005Metric"
		(layer "F.Cu")
		(at 128.48 112.36)
		(descr "Resistor SMD 0402")
		(tags "resistor SMD 0402")
		(property "Reference" "R18"
			(at -1.122484 -0.563751 0)
			(layer "F.SilkS")
			(effects
				(font
					(size 0.7 0.7)
					(thickness 0.15)
				)
				(justify left bottom)
			)
		)
		(property "Value" "R_0R_0402"
			(at -1.011843 1.772047 0)
			(layer "F.Fab")
			(effects
				(font
					(size 0.7 0.7)
					(thickness 0.15)
				)
				(justify left bottom)
			)
		)
		(property "Footprint" "antmicro-footprints:R_0402_1005Metric"
			(at 0 0 0)
			(layer "F.Fab")
			(hide yes)
			(effects
				(font
					(size 1.27 1.27)
					(thickness 0.15)
				)
			)
		)
		(property "Datasheet" "https://industrial.panasonic.com/cdbs/www-data/pdf/RDA0000/AOA0000C301.pdf"
			(at 0 0 0)
			(layer "F.Fab")
			(hide yes)
			(effects
				(font
					(size 1.27 1.27)
					(thickness 0.15)
				)
			)
		)
		(property "Description" "SMD Chip Resistor, Jumper, 0 ohm, 100 mW, 0402 [1005 Metric], Thick Film, General Purpose"
			(at 0 0 0)
			(layer "F.Fab")
			(hide yes)
			(effects
				(font
					(size 1.27 1.27)
					(thickness 0.15)
				)
			)
		)
		(property "MPN" "ERJ2GE0R00X"
			(at 0 0 0)
			(unlocked yes)
			(layer "F.Fab")
			(hide yes)
			(effects
				(font
					(size 1 1)
					(thickness 0.15)
				)
			)
		)
		(property "Manufacturer" "Panasonic"
			(at 0 0 0)
			(unlocked yes)
			(layer "F.Fab")
			(hide yes)
			(effects
				(font
					(size 1 1)
					(thickness 0.15)
				)
			)
		)
		(property "License" "Apache-2.0"
			(at 0 0 0)
			(unlocked yes)
			(layer "F.Fab")
			(hide yes)
			(effects
				(font
					(size 1 1)
					(thickness 0.15)
				)
			)
		)
		(property "Author" "Antmicro"
			(at 0 0 0)
			(unlocked yes)
			(layer "F.Fab")
			(hide yes)
			(effects
				(font
					(size 1 1)
					(thickness 0.15)
				)
			)
		)
		(property "Val" "0R"
			(at 0 0 0)
			(unlocked yes)
			(layer "F.Fab")
			(hide yes)
			(effects
				(font
					(size 1 1)
					(thickness 0.15)
				)
			)
		)
		(property "Tolerance" ""
			(at 0 0 0)
			(unlocked yes)
			(layer "F.Fab")
			(hide yes)
			(effects
				(font
					(size 1 1)
					(thickness 0.15)
				)
			)
		)
		(property "Current" "1A"
			(at 0 0 0)
			(unlocked yes)
			(layer "F.Fab")
			(hide yes)
			(effects
				(font
					(size 1 1)
					(thickness 0.15)
				)
			)
		)
		(property "Public" "False"
			(at 0 0 0)
			(unlocked yes)
			(layer "F.Fab")
			(hide yes)
			(effects
				(font
					(size 1 1)
					(thickness 0.15)
				)
			)
		)
		(sheetname "Root")
		(sheetfile "jetson-orin-baseboard-oculink-expansion.kicad_sch")
		(attr smd)
		(fp_rect
			(start -0.925 -0.47)
			(end 0.925 0.47)
			(stroke
				(width 0.05)
				(type default)
			)
			(fill none)
			(layer "F.CrtYd")
		)
		(fp_rect
			(start -0.5 -0.25)
			(end 0.5 0.25)
			(stroke
				(width 0.15)
				(type solid)
			)
			(fill none)
			(layer "F.Fab")
		)
		(fp_text user "License: Apache-2.0"
			(at -0.95 5.169 0)
			(layer "F.Fab")
			(hide yes)
			(effects
				(font
					(size 0.7 0.7)
					(thickness 0.15)
				)
				(justify left bottom)
			)
		)
		(fp_text user "Author: Antmicro"
			(at -0.95 4.169 0)
			(layer "F.Fab")
			(hide yes)
			(effects
				(font
					(size 0.7 0.7)
					(thickness 0.15)
				)
				(justify left bottom)
			)
		)
		(fp_text user "${REFERENCE}"
			(at -0.95 3.168 0)
			(layer "F.Fab")
			(hide yes)
			(effects
				(font
					(size 0.7 0.7)
					(thickness 0.15)
				)
				(justify left bottom)
			)
		)
		(pad "1" smd roundrect
			(at -0.48 0)
			(size 0.59 0.64)
			(layers "F.Cu" "F.Paste" "F.Mask")
			(roundrect_rratio 0.25)
			(net 23 "+3V3")
			(pintype "passive")
		)
		(pad "2" smd roundrect
			(at 0.48 0)
			(size 0.59 0.64)
			(layers "F.Cu" "F.Paste" "F.Mask")
			(roundrect_rratio 0.25)
			(net 97 "Net-(U2-RXDET)")
			(pintype "passive")
		)
	)
	(footprint "antmicro-footprints:TP_SMD_0.75mm"
		(layer "F.Cu")
		(at 130.45 118.29 180)
		(property "Reference" "TP17"
			(at -1.34 -0.45 0)
			(layer "F.SilkS")
			(effects
				(font
					(size 0.7 0.7)
					(thickness 0.15)
				)
				(justify right top)
			)
		)
		(property "Value" "TP_0.75mm_SMD"
			(at 0 1.2 0)
			(layer "F.Fab")
			(effects
				(font
					(size 0.7 0.7)
					(thickness 0.15)
				)
				(justify right top)
			)
		)
		(property "Footprint" "antmicro-footprints:TP_SMD_0.75mm"
			(at 0 0 0)
			(layer "F.Fab")
			(hide yes)
			(effects
				(font
					(size 1.27 1.27)
					(thickness 0.15)
				)
			)
		)
		(property "Description" "SMT test point"
			(at 0 0 0)
			(layer "F.Fab")
			(hide yes)
			(effects
				(font
					(size 1.27 1.27)
					(thickness 0.15)
				)
			)
		)
		(property "MPN" ""
			(at 0 0 180)
			(unlocked yes)
			(layer "F.Fab")
			(hide yes)
			(effects
				(font
					(size 1 1)
					(thickness 0.15)
				)
			)
		)
		(property "Manufacturer" ""
			(at 0 0 180)
			(unlocked yes)
			(layer "F.Fab")
			(hide yes)
			(effects
				(font
					(size 1 1)
					(thickness 0.15)
				)
			)
		)
		(property "Author" "Antmicro"
			(at 0 0 180)
			(unlocked yes)
			(layer "F.Fab")
			(hide yes)
			(effects
				(font
					(size 1 1)
					(thickness 0.15)
				)
			)
		)
		(property "License" "Apache-2.0"
			(at 0 0 180)
			(unlocked yes)
			(layer "F.Fab")
			(hide yes)
			(effects
				(font
					(size 1 1)
					(thickness 0.15)
				)
			)
		)
		(property "Public" "False"
			(at 0 0 180)
			(unlocked yes)
			(layer "F.Fab")
			(hide yes)
			(effects
				(font
					(size 1 1)
					(thickness 0.15)
				)
			)
		)
		(sheetname "Root")
		(sheetfile "jetson-orin-baseboard-oculink-expansion.kicad_sch")
		(attr exclude_from_pos_files exclude_from_bom)
		(fp_circle
			(center 0 0)
			(end 0.475 0)
			(stroke
				(width 0.05)
				(type default)
			)
			(fill none)
			(layer "F.CrtYd")
		)
		(fp_text user "${REFERENCE}"
			(at -0.4 2.7 0)
			(layer "F.Fab")
			(hide yes)
			(effects
				(font
					(size 0.7 0.7)
					(thickness 0.15)
				)
				(justify right top)
			)
		)
		(fp_text user "License: Apache-2.0"
			(at -0.4 5.101 0)
			(layer "F.Fab")
			(hide yes)
			(effects
				(font
					(size 0.7 0.7)
					(thickness 0.15)
				)
				(justify right top)
			)
		)
		(fp_text user "Author: Antmicro"
			(at -0.4 3.901 0)
			(layer "F.Fab")
			(hide yes)
			(effects
				(font
					(size 0.7 0.7)
					(thickness 0.15)
				)
				(justify right top)
			)
		)
		(pad "1" smd circle
			(at 0 0 180)
			(size 0.75 0.75)
			(layers "F.Cu" "F.Mask")
			(net 95 "Net-(U2-SDA)")
			(pinfunction "1")
			(pintype "passive")
		)
	)
)
